# T6G (Grand Teton) — schematic netlist excerpt (pin names and nets, part order shuffled) for the footprints in the layout excerpt that follows; sources: Cadence DE-HDL packaged netlist, KiCad conversion of 04192023_DAF0TMB3IC0_F0TG_MB_C_brd_V02_OCP.brd

C2258  Q_CAP  22UF 4V 20% X6S  pkg C0402  page 72 : A = PVDDCR_SOC_P1 ; B = GND
C188  Q_CAP  1UF 4V 20% X6S  pkg 0201  page 323 : A = P0V9_CPU1_RT0_2A ; B = GND
R558  Q_RES  4.7K 5% EMPTY  pkg 0402LF  page 55 : A = CPU1_FORCE_SELFREFRESH ; B = PVDD18_S5_P1

(kicad_pcb
	(version 20260206)
	(generator "pcbnew")
	(generator_version "10.0")
	(general
		(thickness 1.6)
		(legacy_teardrops no)
	)
	(paper "A4")
	(title_block
		(title "04192023_DAF0TMB3IC0_F0TG_MB_C_brd_V02_OCP.brd")
		(comment 1 "Grand Teton / footprints 5979-5981 of 8354")
	)
	(layers
		(0 "F.Cu" signal "TOP")
		(4 "In1.Cu" signal "GND")
		(6 "In2.Cu" signal "IN1")
		(8 "In3.Cu" signal "GND1")
		(10 "In4.Cu" signal "IN2")
		(12 "In5.Cu" signal "GND2")
		(14 "In6.Cu" signal "IN3")
		(16 "In7.Cu" signal "GND3")
		(18 "In8.Cu" signal "VCC")
		(20 "In9.Cu" signal "VCC1")
		(22 "In10.Cu" signal "GND4")
		(24 "In11.Cu" signal "IN4")
		(26 "In12.Cu" signal "GND5")
		(28 "In13.Cu" signal "IN5")
		(30 "In14.Cu" signal "GND6")
		(32 "In15.Cu" signal "IN6")
		(34 "In16.Cu" signal "GND7")
		(2 "B.Cu" signal "BOTTOM")
		(9 "F.Adhes" user "F.Adhesive")
		(11 "B.Adhes" user "B.Adhesive")
		(13 "F.Paste" user "Package Geometry/Pastemask Top")
		(15 "B.Paste" user "Package Geometry/Pastemask Bottom")
		(5 "F.SilkS" user "Ref Des/Silkscreen Top")
		(7 "B.SilkS" user "Ref Des/Silkscreen Bottom")
		(1 "F.Mask" user "Board Geometry/Soldermask Top")
		(3 "B.Mask" user "Board Geometry/Soldermask Bottom")
		(17 "Dwgs.User" user "User.Drawings")
		(19 "Cmts.User" user "User.Comments")
		(21 "Eco1.User" user "User.Eco1")
		(23 "Eco2.User" user "User.Eco2")
		(25 "Edge.Cuts" user "Board Geometry/Outline")
		(27 "Margin" user)
		(31 "F.CrtYd" user "Package Geometry/Place Bound Top")
		(29 "B.CrtYd" user "Package Geometry/Place Bound Bottom")
		(35 "F.Fab" user "Ref Des/Assembly Top")
		(33 "B.Fab" user "Ref Des/Assembly Bottom")
	)
	(footprint ""
		(layer "B.Cu")
		(at 67.201034 -198.269352)
		(property "Reference" "R558"
			(at 0 0 0)
			(layer "B.SilkS")
			(hide yes)
			(effects
				(font
					(size 1.27 1.27)
				)
				(justify mirror)
			)
		)
		(property "Value" ""
			(at 0 0 0)
			(layer "B.Fab")
			(effects
				(font
					(size 1.27 1.27)
				)
				(justify mirror)
			)
		)
		(duplicate_pad_numbers_are_jumpers no)
		(fp_line
			(start -0.7874 -0.4064)
			(end -0.7874 0.4064)
			(stroke
				(width 0.1524)
				(type default)
			)
			(layer "B.SilkS")
		)
		(fp_line
			(start -0.7874 0.4064)
			(end 0.7874 0.4064)
			(stroke
				(width 0.1524)
				(type default)
			)
			(layer "B.SilkS")
		)
		(fp_line
			(start 0.7874 -0.4064)
			(end -0.7874 -0.4064)
			(stroke
				(width 0.1524)
				(type default)
			)
			(layer "B.SilkS")
		)
		(fp_line
			(start 0.7874 0.4064)
			(end 0.7874 -0.4064)
			(stroke
				(width 0.1524)
				(type default)
			)
			(layer "B.SilkS")
		)
		(fp_line
			(start -0.67945 -0.3048)
			(end -0.67945 0.3048)
			(stroke
				(width 0.1)
				(type default)
			)
			(layer "B.Fab")
		)
		(fp_line
			(start -0.67945 0.3048)
			(end -0.120396 0.3048)
			(stroke
				(width 0.1)
				(type default)
			)
			(layer "B.Fab")
		)
		(fp_line
			(start -0.12065 -0.3048)
			(end -0.67945 -0.3048)
			(stroke
				(width 0.1)
				(type default)
			)
			(layer "B.Fab")
		)
		(fp_line
			(start -0.12065 -0.2794)
			(end -0.12065 -0.3048)
			(stroke
				(width 0.1)
				(type default)
			)
			(layer "B.Fab")
		)
		(fp_line
			(start -0.120396 0.2794)
			(end 0.12065 0.2794)
			(stroke
				(width 0.1)
				(type default)
			)
			(layer "B.Fab")
		)
		(fp_line
			(start -0.120396 0.3048)
			(end -0.120396 0.2794)
			(stroke
				(width 0.1)
				(type default)
			)
			(layer "B.Fab")
		)
		(fp_line
			(start 0.12065 -0.305054)
			(end 0.12065 -0.2794)
			(stroke
				(width 0.1)
				(type default)
			)
			(layer "B.Fab")
		)
		(fp_line
			(start 0.12065 -0.2794)
			(end -0.12065 -0.2794)
			(stroke
				(width 0.1)
				(type default)
			)
			(layer "B.Fab")
		)
		(fp_line
			(start 0.12065 0.2794)
			(end 0.12065 0.3048)
			(stroke
				(width 0.1)
				(type default)
			)
			(layer "B.Fab")
		)
		(fp_line
			(start 0.12065 0.3048)
			(end 0.67945 0.3048)
			(stroke
				(width 0.1)
				(type default)
			)
			(layer "B.Fab")
		)
		(fp_line
			(start 0.67945 -0.305054)
			(end 0.12065 -0.305054)
			(stroke
				(width 0.1)
				(type default)
			)
			(layer "B.Fab")
		)
		(fp_line
			(start 0.67945 0.3048)
			(end 0.67945 -0.305054)
			(stroke
				(width 0.1)
				(type default)
			)
			(layer "B.Fab")
		)
		(pad "1" smd circle
			(at 0.40005 0 180)
			(size 0 0)
			(layers "B.Cu" "B.Mask" "B.Paste")
			(net "CPU1_FORCE_SELFREFRESH")
		)
		(pad "2" smd circle
			(at -0.40005 0 180)
			(size 0 0)
			(layers "B.Cu" "B.Mask" "B.Paste")
			(net "PVDD18_S5_P1")
		)
	)
	(footprint ""
		(layer "B.Cu")
		(at 108.117386 -253.432564)
		(property "Reference" "C2258"
			(at 0 0 0)
			(layer "B.SilkS")
			(hide yes)
			(effects
				(font
					(size 1.27 1.27)
				)
				(justify mirror)
			)
		)
		(property "Value" ""
			(at 0 0 0)
			(layer "B.Fab")
			(effects
				(font
					(size 1.27 1.27)
				)
				(justify mirror)
			)
		)
		(duplicate_pad_numbers_are_jumpers no)
		(fp_line
			(start -0.7874 -0.4064)
			(end -0.7874 0.4064)
			(stroke
				(width 0.1524)
				(type default)
			)
			(layer "B.SilkS")
		)
		(fp_line
			(start -0.7874 0.4064)
			(end 0.7874 0.4064)
			(stroke
				(width 0.1524)
				(type default)
			)
			(layer "B.SilkS")
		)
		(fp_line
			(start 0.7874 -0.4064)
			(end -0.7874 -0.4064)
			(stroke
				(width 0.1524)
				(type default)
			)
			(layer "B.SilkS")
		)
		(fp_line
			(start 0.7874 0.4064)
			(end 0.7874 -0.4064)
			(stroke
				(width 0.1524)
				(type default)
			)
			(layer "B.SilkS")
		)
		(fp_line
			(start -0.67945 -0.3048)
			(end -0.67945 0.3048)
			(stroke
				(width 0.1)
				(type default)
			)
			(layer "B.Fab")
		)
		(fp_line
			(start -0.67945 0.3048)
			(end -0.120396 0.3048)
			(stroke
				(width 0.1)
				(type default)
			)
			(layer "B.Fab")
		)
		(fp_line
			(start -0.12065 -0.3048)
			(end -0.67945 -0.3048)
			(stroke
				(width 0.1)
				(type default)
			)
			(layer "B.Fab")
		)
		(fp_line
			(start -0.12065 -0.2794)
			(end -0.12065 -0.3048)
			(stroke
				(width 0.1)
				(type default)
			)
			(layer "B.Fab")
		)
		(fp_line
			(start -0.120396 0.2794)
			(end 0.12065 0.2794)
			(stroke
				(width 0.1)
				(type default)
			)
			(layer "B.Fab")
		)
		(fp_line
			(start -0.120396 0.3048)
			(end -0.120396 0.2794)
			(stroke
				(width 0.1)
				(type default)
			)
			(layer "B.Fab")
		)
		(fp_line
			(start 0.12065 -0.305054)
			(end 0.12065 -0.2794)
			(stroke
				(width 0.1)
				(type default)
			)
			(layer "B.Fab")
		)
		(fp_line
			(start 0.12065 -0.2794)
			(end -0.12065 -0.2794)
			(stroke
				(width 0.1)
				(type default)
			)
			(layer "B.Fab")
		)
		(fp_line
			(start 0.12065 0.2794)
			(end 0.12065 0.3048)
			(stroke
				(width 0.1)
				(type default)
			)
			(layer "B.Fab")
		)
		(fp_line
			(start 0.12065 0.3048)
			(end 0.67945 0.3048)
			(stroke
				(width 0.1)
				(type default)
			)
			(layer "B.Fab")
		)
		(fp_line
			(start 0.67945 -0.305054)
			(end 0.12065 -0.305054)
			(stroke
				(width 0.1)
				(type default)
			)
			(layer "B.Fab")
		)
		(fp_line
			(start 0.67945 0.3048)
			(end 0.67945 -0.305054)
			(stroke
				(width 0.1)
				(type default)
			)
			(layer "B.Fab")
		)
		(pad "1" smd circle
			(at 0.40005 0 180)
			(size 0 0)
			(layers "B.Cu" "B.Mask" "B.Paste")
			(net "PVDDCR_SOC_P1")
		)
		(pad "2" smd circle
			(at -0.40005 0 180)
			(size 0 0)
			(layers "B.Cu" "B.Mask" "B.Paste")
			(net "GND")
		)
	)
	(footprint ""
		(layer "B.Cu")
		(at 65.378584 -386.766562 90)
		(property "Reference" "C188"
			(at 0 0 90)
			(layer "B.SilkS")
			(hide yes)
			(effects
				(font
					(size 1.27 1.27)
				)
				(justify mirror)
			)
		)
		(property "Value" ""
			(at 0 0 90)
			(layer "B.Fab")
			(effects
				(font
					(size 1.27 1.27)
				)
				(justify mirror)
			)
		)
		(duplicate_pad_numbers_are_jumpers no)
		(fp_line
			(start 0.299974 -0.150114)
			(end -0.299974 -0.150114)
			(stroke
				(width 0.1)
				(type default)
			)
			(layer "B.Fab")
		)
		(fp_line
			(start -0.299974 -0.150114)
			(end -0.299974 0.150114)
			(stroke
				(width 0.1)
				(type default)
			)
			(layer "B.Fab")
		)
		(fp_line
			(start 0.299974 0.150114)
			(end 0.299974 -0.150114)
			(stroke
				(width 0.1)
				(type default)
			)
			(layer "B.Fab")
		)
		(fp_line
			(start -0.299974 0.150114)
			(end 0.299974 0.150114)
			(stroke
				(width 0.1)
				(type default)
			)
			(layer "B.Fab")
		)
		(pad "1" smd rect
			(at 0.2667 0 270)
			(size 0.3048 0.381)
			(layers "B.Cu" "B.Mask" "B.Paste")
			(net "P0V9_CPU1_RT0_2A")
		)
		(pad "2" smd rect
			(at -0.2667 0 270)
			(size 0.3048 0.381)
			(layers "B.Cu" "B.Mask" "B.Paste")
			(net "GND")
		)
	)
)
